(kicad_pcb
	(version 20241229)
	(generator "pcbnew")
	(generator_version "9.0")
	(general
		(thickness 1.711)
		(legacy_teardrops no)
	)
	(paper "A4")
	(title_block
		(title "Antmicro Baseboard for Jetson AGX Thor")
		(date "2026-02-18")
		(rev "1.1.0")
		(company "Antmicro Ltd")
		(comment 1 "www.antmicro.com")
		(comment 9 "footprints 863-867 of 1170")
	)
	(layers
		(0 "F.Cu" signal)
		(4 "In1.Cu" signal)
		(6 "In2.Cu" signal)
		(8 "In3.Cu" signal)
		(10 "In4.Cu" jumper)
		(12 "In5.Cu" signal)
		(14 "In6.Cu" signal)
		(16 "In7.Cu" signal)
		(18 "In8.Cu" signal)
		(2 "B.Cu" signal)
		(9 "F.Adhes" user "F.Adhesive")
		(11 "B.Adhes" user "B.Adhesive")
		(13 "F.Paste" user)
		(15 "B.Paste" user)
		(5 "F.SilkS" user "F.Silkscreen")
		(7 "B.SilkS" user "B.Silkscreen")
		(1 "F.Mask" user)
		(3 "B.Mask" user)
		(17 "Dwgs.User" user "User.Drawings")
		(19 "Cmts.User" user "User.Comments")
		(21 "Eco1.User" user "User.Eco1")
		(23 "Eco2.User" user "User.Eco2")
		(25 "Edge.Cuts" user)
		(27 "Margin" user)
		(31 "F.CrtYd" user "F.Courtyard")
		(29 "B.CrtYd" user "B.Courtyard")
		(35 "F.Fab" user)
		(33 "B.Fab" user)
	)
	(footprint "antmicro-footprints:R_0402_1005Metric"
		(layer "B.Cu")
		(at 124.6 108.8 180)
		(descr "Resistor SMD 0402")
		(tags "resistor SMD 0402")
		(property "Reference" "R210"
			(at -3.9 -0.4 0)
			(layer "B.SilkS")
			(effects
				(font
					(size 0.7 0.7)
					(thickness 0.15)
				)
				(justify left bottom mirror)
			)
		)
		(property "Value" "R_47k_0402"
			(at -1.011843 -1.772046 0)
			(layer "B.Fab")
			(effects
				(font
					(size 0.7 0.7)
					(thickness 0.15)
				)
				(justify left bottom mirror)
			)
		)
		(property "Datasheet" "https://www.bourns.com/docs/product-datasheets/cr.pdf"
			(at 0 0 0)
			(layer "B.Fab")
			(hide yes)
			(effects
				(font
					(size 1.27 1.27)
					(thickness 0.15)
				)
				(justify mirror)
			)
		)
		(property "Description" "SMD Chip Resistor, 47 kohm, ± 1%, 62.5 mW, 0402 [1005 Metric], Thick Film, General Purpose"
			(at 0 0 0)
			(layer "B.Fab")
			(hide yes)
			(effects
				(font
					(size 1.27 1.27)
					(thickness 0.15)
				)
				(justify mirror)
			)
		)
		(property "Manufacturer" "Bourns"
			(at 0 0 0)
			(unlocked yes)
			(layer "B.Fab")
			(hide yes)
			(effects
				(font
					(size 1 1)
					(thickness 0.15)
				)
				(justify mirror)
			)
		)
		(property "MPN" "CR0402-FX-4702GLF"
			(at 0 0 0)
			(unlocked yes)
			(layer "B.Fab")
			(hide yes)
			(effects
				(font
					(size 1 1)
					(thickness 0.15)
				)
				(justify mirror)
			)
		)
		(property "Val" "47k"
			(at 0 0 0)
			(unlocked yes)
			(layer "B.Fab")
			(hide yes)
			(effects
				(font
					(size 1 1)
					(thickness 0.15)
				)
				(justify mirror)
			)
		)
		(property "License" "Apache-2.0"
			(at 0 0 0)
			(unlocked yes)
			(layer "B.Fab")
			(hide yes)
			(effects
				(font
					(size 1 1)
					(thickness 0.15)
				)
				(justify mirror)
			)
		)
		(property "Author" "Antmicro"
			(at 0 0 0)
			(unlocked yes)
			(layer "B.Fab")
			(hide yes)
			(effects
				(font
					(size 1 1)
					(thickness 0.15)
				)
				(justify mirror)
			)
		)
		(property "Tolerance" "1%"
			(at 0 0 0)
			(unlocked yes)
			(layer "B.Fab")
			(hide yes)
			(effects
				(font
					(size 1 1)
					(thickness 0.15)
				)
				(justify mirror)
			)
		)
		(sheetname "/M.2/")
		(sheetfile "m2.kicad_sch")
		(attr smd exclude_from_pos_files exclude_from_bom dnp)
		(fp_poly
			(pts
				(xy -0.925 0.47) (xy 0.925 0.47) (xy 0.925 -0.47) (xy -0.925 -0.47)
			)
			(stroke
				(width 0.05)
				(type default)
			)
			(fill no)
			(layer "B.CrtYd")
		)
		(fp_poly
			(pts
				(xy -0.5 0.25) (xy 0.5 0.25) (xy 0.5 -0.25) (xy -0.5 -0.25)
			)
			(stroke
				(width 0.15)
				(type solid)
			)
			(fill no)
			(layer "B.Fab")
		)
		(fp_text user "Author: Antmicro"
			(at -0.95 -4.169 0)
			(layer "B.Fab")
			(effects
				(font
					(size 0.7 0.7)
					(thickness 0.15)
				)
				(justify left bottom mirror)
			)
		)
		(fp_text user "${REFERENCE}"
			(at -0.95 -3.168 0)
			(layer "B.Fab")
			(effects
				(font
					(size 0.7 0.7)
					(thickness 0.15)
				)
				(justify left bottom mirror)
			)
		)
		(fp_text user "License: Apache-2.0"
			(at -0.949999 -5.169 0)
			(layer "B.Fab")
			(effects
				(font
					(size 0.7 0.7)
					(thickness 0.15)
				)
				(justify left bottom mirror)
			)
		)
		(pad "1" smd roundrect
			(at -0.48 0 180)
			(size 0.59 0.64)
			(layers "B.Cu" "B.Mask" "B.Paste")
			(roundrect_rratio 0.25)
			(net 2 "+3V3")
			(pintype "passive")
		)
		(pad "2" smd roundrect
			(at 0.48 0 180)
			(size 0.59 0.64)
			(layers "B.Cu" "B.Mask" "B.Paste")
			(roundrect_rratio 0.25)
			(net 825 "/M.2/~{CLKREQ_M}")
			(pintype "passive")
		)
	)
	(footprint "antmicro-footprints:R_0402_1005Metric"
		(layer "B.Cu")
		(at 142.8 71.7 -90)
		(descr "Resistor SMD 0402")
		(tags "resistor SMD 0402")
		(property "Reference" "R290"
			(at -1 -2.5 90)
			(layer "B.SilkS")
			(effects
				(font
					(size 0.7 0.7)
					(thickness 0.15)
				)
				(justify left bottom mirror)
			)
		)
		(property "Value" "R_0R_0402"
			(at -1.011843 -1.772047 90)
			(layer "B.Fab")
			(effects
				(font
					(size 0.7 0.7)
					(thickness 0.15)
				)
				(justify left bottom mirror)
			)
		)
		(property "Datasheet" "https://industrial.panasonic.com/cdbs/www-data/pdf/RDA0000/AOA0000C301.pdf"
			(at 0 0 90)
			(layer "B.Fab")
			(hide yes)
			(effects
				(font
					(size 1.27 1.27)
					(thickness 0.15)
				)
				(justify mirror)
			)
		)
		(property "Description" "SMD Chip Resistor, Jumper, 0 ohm, 100 mW, 0402 [1005 Metric], Thick Film, General Purpose"
			(at 0 0 90)
			(layer "B.Fab")
			(hide yes)
			(effects
				(font
					(size 1.27 1.27)
					(thickness 0.15)
				)
				(justify mirror)
			)
		)
		(property "MPN" "ERJ2GE0R00X"
			(at 0 0 90)
			(unlocked yes)
			(layer "B.Fab")
			(hide yes)
			(effects
				(font
					(size 1 1)
					(thickness 0.15)
				)
				(justify mirror)
			)
		)
		(property "Manufacturer" "Panasonic"
			(at 0 0 90)
			(unlocked yes)
			(layer "B.Fab")
			(hide yes)
			(effects
				(font
					(size 1 1)
					(thickness 0.15)
				)
				(justify mirror)
			)
		)
		(property "License" "Apache-2.0"
			(at 0 0 90)
			(unlocked yes)
			(layer "B.Fab")
			(hide yes)
			(effects
				(font
					(size 1 1)
					(thickness 0.15)
				)
				(justify mirror)
			)
		)
		(property "Author" "Antmicro"
			(at 0 0 90)
			(unlocked yes)
			(layer "B.Fab")
			(hide yes)
			(effects
				(font
					(size 1 1)
					(thickness 0.15)
				)
				(justify mirror)
			)
		)
		(property "Val" "0R"
			(at 0 0 90)
			(unlocked yes)
			(layer "B.Fab")
			(hide yes)
			(effects
				(font
					(size 1 1)
					(thickness 0.15)
				)
				(justify mirror)
			)
		)
		(property "Tolerance" "~"
			(at 0 0 90)
			(unlocked yes)
			(layer "B.Fab")
			(hide yes)
			(effects
				(font
					(size 1 1)
					(thickness 0.15)
				)
				(justify mirror)
			)
		)
		(property "Current" "1A"
			(at 0 0 90)
			(unlocked yes)
			(layer "B.Fab")
			(hide yes)
			(effects
				(font
					(size 1 1)
					(thickness 0.15)
				)
				(justify mirror)
			)
		)
		(sheetname "/SoM_IO2/")
		(sheetfile "som_io2.kicad_sch")
		(attr smd exclude_from_pos_files exclude_from_bom dnp)
		(fp_rect
			(start -0.925 0.47)
			(end 0.925 -0.47)
			(stroke
				(width 0.05)
				(type default)
			)
			(fill no)
			(layer "B.CrtYd")
		)
		(fp_rect
			(start -0.5 0.25)
			(end 0.5 -0.25)
			(stroke
				(width 0.15)
				(type solid)
			)
			(fill no)
			(layer "B.Fab")
		)
		(fp_text user "Author: Antmicro"
			(at -0.95 -4.169 90)
			(layer "B.Fab")
			(effects
				(font
					(size 0.7 0.7)
					(thickness 0.15)
				)
				(justify left bottom mirror)
			)
		)
		(fp_text user "${REFERENCE}"
			(at -0.95 -3.168 90)
			(layer "B.Fab")
			(effects
				(font
					(size 0.7 0.7)
					(thickness 0.15)
				)
				(justify left bottom mirror)
			)
		)
		(fp_text user "License: Apache-2.0"
			(at -0.95 -5.169 90)
			(layer "B.Fab")
			(effects
				(font
					(size 0.7 0.7)
					(thickness 0.15)
				)
				(justify left bottom mirror)
			)
		)
		(pad "1" smd roundrect
			(at -0.48 0 270)
			(size 0.59 0.64)
			(layers "B.Cu" "B.Mask" "B.Paste")
			(roundrect_rratio 0.25)
			(net 11 "+1V8")
			(pintype "passive")
		)
		(pad "2" smd roundrect
			(at 0.48 0 270)
			(size 0.59 0.64)
			(layers "B.Cu" "B.Mask" "B.Paste")
			(roundrect_rratio 0.25)
			(net 606 "/SoM_IO2/NVJTAG_SEL")
			(pintype "passive")
		)
	)
	(footprint "antmicro-footprints:C_0402_1005Metric"
		(layer "B.Cu")
		(at 110.25 98.5)
		(descr "Capacitor SMD 0402")
		(tags "capacitor SMD 0402")
		(property "Reference" "C184"
			(at -0.95 -0.4 0)
			(layer "B.SilkS")
			(effects
				(font
					(size 0.7 0.7)
					(thickness 0.15)
				)
				(justify left top mirror)
			)
		)
		(property "Value" "C_220n_0402"
			(at -1.022927 -2.155213 0)
			(layer "B.Fab")
			(effects
				(font
					(size 0.7 0.7)
					(thickness 0.15)
				)
				(justify right top mirror)
			)
		)
		(property "Datasheet" "https://www.yageo.com/en/Chart/Download/pdf/CC0402KRX5R6BB224"
			(at 0 0 0)
			(layer "B.Fab")
			(hide yes)
			(effects
				(font
					(size 1.27 1.27)
					(thickness 0.15)
				)
				(justify mirror)
			)
		)
		(property "Description" "SMD Multilayer Ceramic Capacitor, 0.22 µF, 10 V, 0402 [1005 Metric], ± 10%, X5R, CC Series"
			(at 0 0 0)
			(layer "B.Fab")
			(hide yes)
			(effects
				(font
					(size 1.27 1.27)
					(thickness 0.15)
				)
				(justify mirror)
			)
		)
		(property "MPN" "CC0402KRX5R6BB224"
			(at 0 0 0)
			(unlocked yes)
			(layer "B.Fab")
			(hide yes)
			(effects
				(font
					(size 1 1)
					(thickness 0.15)
				)
				(justify mirror)
			)
		)
		(property "Val" "220n"
			(at 0 0 0)
			(unlocked yes)
			(layer "B.Fab")
			(hide yes)
			(effects
				(font
					(size 1 1)
					(thickness 0.15)
				)
				(justify mirror)
			)
		)
		(property "Voltage" "25V"
			(at 0 0 0)
			(unlocked yes)
			(layer "B.Fab")
			(hide yes)
			(effects
				(font
					(size 1 1)
					(thickness 0.15)
				)
				(justify mirror)
			)
		)
		(property "Dielectric" "X7R"
			(at 0 0 0)
			(unlocked yes)
			(layer "B.Fab")
			(hide yes)
			(effects
				(font
					(size 1 1)
					(thickness 0.15)
				)
				(justify mirror)
			)
		)
		(property "Manufacturer" "YAGEO"
			(at 0 0 0)
			(unlocked yes)
			(layer "B.Fab")
			(hide yes)
			(effects
				(font
					(size 1 1)
					(thickness 0.15)
				)
				(justify mirror)
			)
		)
		(property "License" "Apache-2.0"
			(at 0 0 0)
			(unlocked yes)
			(layer "B.Fab")
			(hide yes)
			(effects
				(font
					(size 1 1)
					(thickness 0.15)
				)
				(justify mirror)
			)
		)
		(property "Author" "Antmicro"
			(at 0 0 0)
			(unlocked yes)
			(layer "B.Fab")
			(hide yes)
			(effects
				(font
					(size 1 1)
					(thickness 0.15)
				)
				(justify mirror)
			)
		)
		(property "Public" "False"
			(at 0 0 0)
			(unlocked yes)
			(layer "B.Fab")
			(hide yes)
			(effects
				(font
					(size 1 1)
					(thickness 0.15)
				)
				(justify mirror)
			)
		)
		(sheetname "/M.2/")
		(sheetfile "m2.kicad_sch")
		(attr smd)
		(fp_poly
			(pts
				(xy -0.925 0.47) (xy -0.925 -0.47) (xy 0.925 -0.47) (xy 0.925 0.47)
			)
			(stroke
				(width 0.05)
				(type default)
			)
			(fill no)
			(layer "B.CrtYd")
		)
		(fp_line
			(start -0.494 -0.248)
			(end -0.494 0.25)
			(stroke
				(width 0.15)
				(type solid)
			)
			(layer "B.Fab")
		)
		(fp_line
			(start -0.494 0.25)
			(end 0.504 0.25)
			(stroke
				(width 0.15)
				(type solid)
			)
			(layer "B.Fab")
		)
		(fp_line
			(start 0.504 -0.248)
			(end -0.494 -0.248)
			(stroke
				(width 0.15)
				(type solid)
			)
			(layer "B.Fab")
		)
		(fp_line
			(start 0.504 0.25)
			(end 0.504 -0.248)
			(stroke
				(width 0.15)
				(type solid)
			)
			(layer "B.Fab")
		)
		(fp_text user "License: Apache-2.0"
			(at -0.939 -5.799 0)
			(layer "B.Fab")
			(effects
				(font
					(size 0.7 0.7)
					(thickness 0.15)
				)
				(justify right top mirror)
			)
		)
		(fp_text user "Author: Antmicro"
			(at -0.939 -3.399 0)
			(layer "B.Fab")
			(effects
				(font
					(size 0.7 0.7)
					(thickness 0.15)
				)
				(justify right top mirror)
			)
		)
		(fp_text user "${REFERENCE}"
			(at -0.939 -4.599 0)
			(layer "B.Fab")
			(effects
				(font
					(size 0.7 0.7)
					(thickness 0.15)
				)
				(justify right top mirror)
			)
		)
		(pad "1" smd roundrect
			(at -0.48 0)
			(size 0.59 0.64)
			(layers "B.Cu" "B.Mask" "B.Paste")
			(roundrect_rratio 0.25)
			(net 410 "/M.2/PCIe_{C5x4}.TX3+")
			(pintype "passive")
		)
		(pad "2" smd roundrect
			(at 0.48 0)
			(size 0.59 0.64)
			(layers "B.Cu" "B.Mask" "B.Paste")
			(roundrect_rratio 0.25)
			(net 408 "/M.2/M2_M_PET3_P")
			(pintype "passive")
		)
	)
	(footprint "antmicro-footprints:R_0402_1005Metric"
		(layer "B.Cu")
		(at 115.78 116.58)
		(descr "Resistor SMD 0402")
		(tags "resistor SMD 0402")
		(property "Reference" "R211"
			(at 3.12 -0.38 0)
			(layer "B.SilkS")
			(effects
				(font
					(size 0.7 0.7)
					(thickness 0.15)
				)
				(justify right top mirror)
			)
		)
		(property "Value" "R_200R_0402"
			(at -1.011843 -1.772047 0)
			(layer "B.Fab")
			(effects
				(font
					(size 0.7 0.7)
					(thickness 0.15)
				)
				(justify right top mirror)
			)
		)
		(property "Datasheet" "https://www.bourns.com/docs/product-datasheets/cr.pdf"
			(at 0 0 0)
			(layer "B.Fab")
			(hide yes)
			(effects
				(font
					(size 1.27 1.27)
					(thickness 0.15)
				)
				(justify mirror)
			)
		)
		(property "Description" "SMD Chip Resistor, 200 ohm, ± 1%, 62.5 mW, 0402 [1005 Metric], Thick Film, General Purpose"
			(at 0 0 0)
			(layer "B.Fab")
			(hide yes)
			(effects
				(font
					(size 1.27 1.27)
					(thickness 0.15)
				)
				(justify mirror)
			)
		)
		(property "Manufacturer" "Bourns"
			(at 0 0 180)
			(unlocked yes)
			(layer "B.Fab")
			(hide yes)
			(effects
				(font
					(size 1 1)
					(thickness 0.15)
				)
				(justify mirror)
			)
		)
		(property "MPN" "CR0402-FX-2000GLF"
			(at 0 0 180)
			(unlocked yes)
			(layer "B.Fab")
			(hide yes)
			(effects
				(font
					(size 1 1)
					(thickness 0.15)
				)
				(justify mirror)
			)
		)
		(property "Val" "200R"
			(at 0 0 180)
			(unlocked yes)
			(layer "B.Fab")
			(hide yes)
			(effects
				(font
					(size 1 1)
					(thickness 0.15)
				)
				(justify mirror)
			)
		)
		(property "License" "Apache-2.0"
			(at 0 0 180)
			(unlocked yes)
			(layer "B.Fab")
			(hide yes)
			(effects
				(font
					(size 1 1)
					(thickness 0.15)
				)
				(justify mirror)
			)
		)
		(property "Author" "Antmicro"
			(at 0 0 180)
			(unlocked yes)
			(layer "B.Fab")
			(hide yes)
			(effects
				(font
					(size 1 1)
					(thickness 0.15)
				)
				(justify mirror)
			)
		)
		(property "Tolerance" "1%"
			(at 0 0 180)
			(unlocked yes)
			(layer "B.Fab")
			(hide yes)
			(effects
				(font
					(size 1 1)
					(thickness 0.15)
				)
				(justify mirror)
			)
		)
		(sheetname "/M.2/")
		(sheetfile "m2.kicad_sch")
		(attr smd)
		(fp_rect
			(start -0.925 0.47)
			(end 0.925 -0.47)
			(stroke
				(width 0.05)
				(type default)
			)
			(fill no)
			(layer "B.CrtYd")
		)
		(fp_rect
			(start -0.5 0.25)
			(end 0.5 -0.25)
			(stroke
				(width 0.15)
				(type solid)
			)
			(fill no)
			(layer "B.Fab")
		)
		(fp_text user "Author: Antmicro"
			(at -0.95 -4.169 0)
			(layer "B.Fab")
			(effects
				(font
					(size 0.7 0.7)
					(thickness 0.15)
				)
				(justify right top mirror)
			)
		)
		(fp_text user "License: Apache-2.0"
			(at -0.95 -5.169 0)
			(layer "B.Fab")
			(effects
				(font
					(size 0.7 0.7)
					(thickness 0.15)
				)
				(justify right top mirror)
			)
		)
		(fp_text user "${REFERENCE}"
			(at -0.95 -3.168 0)
			(layer "B.Fab")
			(effects
				(font
					(size 0.7 0.7)
					(thickness 0.15)
				)
				(justify right top mirror)
			)
		)
		(pad "1" smd roundrect
			(at -0.48 0)
			(size 0.59 0.64)
			(layers "B.Cu" "B.Mask" "B.Paste")
			(roundrect_rratio 0.25)
			(net 544 "Net-(D32-A)")
			(pintype "passive")
		)
		(pad "2" smd roundrect
			(at 0.48 0)
			(size 0.59 0.64)
			(layers "B.Cu" "B.Mask" "B.Paste")
			(roundrect_rratio 0.25)
			(net 2 "+3V3")
			(pintype "passive")
		)
	)
	(footprint "antmicro-footprints:C_0402_1005Metric"
		(layer "B.Cu")
		(at 126.5635 141.8 180)
		(descr "Capacitor SMD 0402")
		(tags "capacitor SMD 0402")
		(property "Reference" "C207"
			(at -1.899968 0.584 0)
			(layer "B.SilkS")
			(effects
				(font
					(size 0.7 0.7)
					(thickness 0.15)
				)
				(justify left bottom mirror)
			)
		)
		(property "Value" "C_10u_0402"
			(at -1.022927 -2.155213 0)
			(layer "B.Fab")
			(effects
				(font
					(size 0.7 0.7)
					(thickness 0.15)
				)
				(justify left bottom mirror)
			)
		)
		(property "Datasheet" "https://www.yageo.com/en/Chart/Download/pdf/CC0402MRX5R5BB106"
			(at 0 0 0)
			(layer "B.Fab")
			(hide yes)
			(effects
				(font
					(size 1.27 1.27)
					(thickness 0.15)
				)
				(justify mirror)
			)
		)
		(property "Description" "SMD Multilayer Ceramic Capacitor, 10 µF, 6.3 V, 0402 [1005 Metric], ± 20%, X5R, CC Series"
			(at 0 0 0)
			(layer "B.Fab")
			(hide yes)
			(effects
				(font
					(size 1.27 1.27)
					(thickness 0.15)
				)
				(justify mirror)
			)
		)
		(property "MPN" "CC0402MRX5R5BB106"
			(at 0 0 0)
			(unlocked yes)
			(layer "B.Fab")
			(hide yes)
			(effects
				(font
					(size 1 1)
					(thickness 0.15)
				)
				(justify mirror)
			)
		)
		(property "Manufacturer" "YAGEO"
			(at 0 0 0)
			(unlocked yes)
			(layer "B.Fab")
			(hide yes)
			(effects
				(font
					(size 1 1)
					(thickness 0.15)
				)
				(justify mirror)
			)
		)
		(property "License" "Apache-2.0"
			(at 0 0 0)
			(unlocked yes)
			(layer "B.Fab")
			(hide yes)
			(effects
				(font
					(size 1 1)
					(thickness 0.15)
				)
				(justify mirror)
			)
		)
		(property "Author" "Antmicro"
			(at 0 0 0)
			(unlocked yes)
			(layer "B.Fab")
			(hide yes)
			(effects
				(font
					(size 1 1)
					(thickness 0.15)
				)
				(justify mirror)
			)
		)
		(property "Val" "10u"
			(at 0 0 0)
			(unlocked yes)
			(layer "B.Fab")
			(hide yes)
			(effects
				(font
					(size 1 1)
					(thickness 0.15)
				)
				(justify mirror)
			)
		)
		(property "Voltage" "16V"
			(at 0 0 0)
			(unlocked yes)
			(layer "B.Fab")
			(hide yes)
			(effects
				(font
					(size 1 1)
					(thickness 0.15)
				)
				(justify mirror)
			)
		)
		(property "Dielectric" ""
			(at 0 0 0)
			(unlocked yes)
			(layer "B.Fab")
			(hide yes)
			(effects
				(font
					(size 1 1)
					(thickness 0.15)
				)
				(justify mirror)
			)
		)
		(sheetname "/Peripherals/")
		(sheetfile "peripherals.kicad_sch")
		(attr smd)
		(fp_rect
			(start -0.925 0.47)
			(end 0.925 -0.47)
			(stroke
				(width 0.05)
				(type default)
			)
			(fill no)
			(layer "B.CrtYd")
		)
		(fp_line
			(start 0.504 0.25)
			(end 0.504 -0.248)
			(stroke
				(width 0.15)
				(type solid)
			)
			(layer "B.Fab")
		)
		(fp_line
			(start 0.504 -0.248)
			(end -0.494 -0.248)
			(stroke
				(width 0.15)
				(type solid)
			)
			(layer "B.Fab")
		)
		(fp_line
			(start -0.494 0.25)
			(end 0.504 0.25)
			(stroke
				(width 0.15)
				(type solid)
			)
			(layer "B.Fab")
		)
		(fp_line
			(start -0.494 -0.248)
			(end -0.494 0.25)
			(stroke
				(width 0.15)
				(type solid)
			)
			(layer "B.Fab")
		)
		(fp_text user "${REFERENCE}"
			(at -0.939 -4.599 0)
			(layer "B.Fab")
			(effects
				(font
					(size 0.7 0.7)
					(thickness 0.15)
				)
				(justify left bottom mirror)
			)
		)
		(fp_text user "License: Apache-2.0"
			(at -0.939 -5.799 0)
			(layer "B.Fab")
			(effects
				(font
					(size 0.7 0.7)
					(thickness 0.15)
				)
				(justify left bottom mirror)
			)
		)
		(fp_text user "Author: Antmicro"
			(at -0.939 -3.399 0)
			(layer "B.Fab")
			(effects
				(font
					(size 0.7 0.7)
					(thickness 0.15)
				)
				(justify left bottom mirror)
			)
		)
		(pad "1" smd roundrect
			(at -0.48 0 180)
			(size 0.59 0.64)
			(layers "B.Cu" "B.Mask" "B.Paste")
			(roundrect_rratio 0.25)
			(net 1 "GND")
			(pintype "passive")
		)
		(pad "2" smd roundrect
			(at 0.48 0 180)
			(size 0.59 0.64)
			(layers "B.Cu" "B.Mask" "B.Paste")
			(roundrect_rratio 0.25)
			(net 2 "+3V3")
			(pintype "passive")
		)
	)
)
